# T6G (Grand Teton) — schematic netlist excerpt (pin names and nets, part order shuffled) for the footprints in the layout excerpt that follows; sources: Cadence DE-HDL packaged netlist, KiCad conversion of 04192023_DAF0TMB3IC0_F0TG_MB_C_brd_V02_OCP.brd

C6120  Q_CAP  0.01UF 50V 10% X7R  pkg C0402  page 179 : A = P1V2_CPU0_USB2_DVDD12 ; B = GND
C268  Q_CAP  22UF 4V 20% X6S  pkg C0402  page 69 : A = PVDDCR_CPU0_P0 ; B = GND

(kicad_pcb
	(version 20260206)
	(generator "pcbnew")
	(generator_version "10.0")
	(general
		(thickness 1.6)
		(legacy_teardrops no)
	)
	(paper "A4")
	(title_block
		(title "04192023_DAF0TMB3IC0_F0TG_MB_C_brd_V02_OCP.brd")
		(comment 1 "Grand Teton / footprints 5590-5591 of 8354")
	)
	(layers
		(0 "F.Cu" signal "TOP")
		(4 "In1.Cu" signal "GND")
		(6 "In2.Cu" signal "IN1")
		(8 "In3.Cu" signal "GND1")
		(10 "In4.Cu" signal "IN2")
		(12 "In5.Cu" signal "GND2")
		(14 "In6.Cu" signal "IN3")
		(16 "In7.Cu" signal "GND3")
		(18 "In8.Cu" signal "VCC")
		(20 "In9.Cu" signal "VCC1")
		(22 "In10.Cu" signal "GND4")
		(24 "In11.Cu" signal "IN4")
		(26 "In12.Cu" signal "GND5")
		(28 "In13.Cu" signal "IN5")
		(30 "In14.Cu" signal "GND6")
		(32 "In15.Cu" signal "IN6")
		(34 "In16.Cu" signal "GND7")
		(2 "B.Cu" signal "BOTTOM")
		(9 "F.Adhes" user "F.Adhesive")
		(11 "B.Adhes" user "B.Adhesive")
		(13 "F.Paste" user "Package Geometry/Pastemask Top")
		(15 "B.Paste" user "Package Geometry/Pastemask Bottom")
		(5 "F.SilkS" user "Ref Des/Silkscreen Top")
		(7 "B.SilkS" user "Ref Des/Silkscreen Bottom")
		(1 "F.Mask" user "Board Geometry/Soldermask Top")
		(3 "B.Mask" user "Board Geometry/Soldermask Bottom")
		(17 "Dwgs.User" user "User.Drawings")
		(19 "Cmts.User" user "User.Comments")
		(21 "Eco1.User" user "User.Eco1")
		(23 "Eco2.User" user "User.Eco2")
		(25 "Edge.Cuts" user "Board Geometry/Outline")
		(27 "Margin" user)
		(31 "F.CrtYd" user "Package Geometry/Place Bound Top")
		(29 "B.CrtYd" user "Package Geometry/Place Bound Bottom")
		(35 "F.Fab" user "Ref Des/Assembly Top")
		(33 "B.Fab" user "Ref Des/Assembly Bottom")
	)
	(footprint ""
		(layer "B.Cu")
		(at 116.702078 -26.025856 90)
		(property "Reference" "C6120"
			(at 0 0 90)
			(layer "B.SilkS")
			(hide yes)
			(effects
				(font
					(size 1.27 1.27)
				)
				(justify mirror)
			)
		)
		(property "Value" ""
			(at 0 0 90)
			(layer "B.Fab")
			(effects
				(font
					(size 1.27 1.27)
				)
				(justify mirror)
			)
		)
		(duplicate_pad_numbers_are_jumpers no)
		(fp_line
			(start 0.7874 -0.4064)
			(end -0.7874 -0.4064)
			(stroke
				(width 0.1524)
				(type default)
			)
			(layer "B.SilkS")
		)
		(fp_line
			(start -0.7874 -0.4064)
			(end -0.7874 0.4064)
			(stroke
				(width 0.1524)
				(type default)
			)
			(layer "B.SilkS")
		)
		(fp_line
			(start 0.7874 0.4064)
			(end 0.7874 -0.4064)
			(stroke
				(width 0.1524)
				(type default)
			)
			(layer "B.SilkS")
		)
		(fp_line
			(start -0.7874 0.4064)
			(end 0.7874 0.4064)
			(stroke
				(width 0.1524)
				(type default)
			)
			(layer "B.SilkS")
		)
		(fp_line
			(start 0.67945 -0.305054)
			(end 0.12065 -0.305054)
			(stroke
				(width 0.1)
				(type default)
			)
			(layer "B.Fab")
		)
		(fp_line
			(start 0.12065 -0.305054)
			(end 0.12065 -0.2794)
			(stroke
				(width 0.1)
				(type default)
			)
			(layer "B.Fab")
		)
		(fp_line
			(start -0.12065 -0.3048)
			(end -0.67945 -0.3048)
			(stroke
				(width 0.1)
				(type default)
			)
			(layer "B.Fab")
		)
		(fp_line
			(start -0.67945 -0.3048)
			(end -0.67945 0.3048)
			(stroke
				(width 0.1)
				(type default)
			)
			(layer "B.Fab")
		)
		(fp_line
			(start 0.12065 -0.2794)
			(end -0.12065 -0.2794)
			(stroke
				(width 0.1)
				(type default)
			)
			(layer "B.Fab")
		)
		(fp_line
			(start -0.12065 -0.2794)
			(end -0.12065 -0.3048)
			(stroke
				(width 0.1)
				(type default)
			)
			(layer "B.Fab")
		)
		(fp_line
			(start 0.12065 0.2794)
			(end 0.12065 0.3048)
			(stroke
				(width 0.1)
				(type default)
			)
			(layer "B.Fab")
		)
		(fp_line
			(start -0.120396 0.2794)
			(end 0.12065 0.2794)
			(stroke
				(width 0.1)
				(type default)
			)
			(layer "B.Fab")
		)
		(fp_line
			(start 0.67945 0.3048)
			(end 0.67945 -0.305054)
			(stroke
				(width 0.1)
				(type default)
			)
			(layer "B.Fab")
		)
		(fp_line
			(start 0.12065 0.3048)
			(end 0.67945 0.3048)
			(stroke
				(width 0.1)
				(type default)
			)
			(layer "B.Fab")
		)
		(fp_line
			(start -0.120396 0.3048)
			(end -0.120396 0.2794)
			(stroke
				(width 0.1)
				(type default)
			)
			(layer "B.Fab")
		)
		(fp_line
			(start -0.67945 0.3048)
			(end -0.120396 0.3048)
			(stroke
				(width 0.1)
				(type default)
			)
			(layer "B.Fab")
		)
		(pad "1" smd circle
			(at 0.40005 0 270)
			(size 0 0)
			(layers "B.Cu" "B.Mask" "B.Paste")
			(net "P1V2_CPU0_USB2_DVDD12")
		)
		(pad "2" smd circle
			(at -0.40005 0 270)
			(size 0 0)
			(layers "B.Cu" "B.Mask" "B.Paste")
			(net "GND")
		)
	)
	(footprint ""
		(layer "B.Cu")
		(at 356.406958 -249.36831 180)
		(property "Reference" "C268"
			(at 0 0 0)
			(layer "B.SilkS")
			(hide yes)
			(effects
				(font
					(size 1.27 1.27)
				)
				(justify mirror)
			)
		)
		(property "Value" ""
			(at 0 0 0)
			(layer "B.Fab")
			(effects
				(font
					(size 1.27 1.27)
				)
				(justify mirror)
			)
		)
		(duplicate_pad_numbers_are_jumpers no)
		(fp_line
			(start 0.7874 0.4064)
			(end 0.7874 -0.4064)
			(stroke
				(width 0.1524)
				(type default)
			)
			(layer "B.SilkS")
		)
		(fp_line
			(start 0.7874 -0.4064)
			(end -0.7874 -0.4064)
			(stroke
				(width 0.1524)
				(type default)
			)
			(layer "B.SilkS")
		)
		(fp_line
			(start -0.7874 0.4064)
			(end 0.7874 0.4064)
			(stroke
				(width 0.1524)
				(type default)
			)
			(layer "B.SilkS")
		)
		(fp_line
			(start -0.7874 -0.4064)
			(end -0.7874 0.4064)
			(stroke
				(width 0.1524)
				(type default)
			)
			(layer "B.SilkS")
		)
		(fp_line
			(start 0.67945 0.3048)
			(end 0.67945 -0.305054)
			(stroke
				(width 0.1)
				(type default)
			)
			(layer "B.Fab")
		)
		(fp_line
			(start 0.67945 -0.305054)
			(end 0.12065 -0.305054)
			(stroke
				(width 0.1)
				(type default)
			)
			(layer "B.Fab")
		)
		(fp_line
			(start 0.12065 0.3048)
			(end 0.67945 0.3048)
			(stroke
				(width 0.1)
				(type default)
			)
			(layer "B.Fab")
		)
		(fp_line
			(start 0.12065 0.2794)
			(end 0.12065 0.3048)
			(stroke
				(width 0.1)
				(type default)
			)
			(layer "B.Fab")
		)
		(fp_line
			(start 0.12065 -0.2794)
			(end -0.12065 -0.2794)
			(stroke
				(width 0.1)
				(type default)
			)
			(layer "B.Fab")
		)
		(fp_line
			(start 0.12065 -0.305054)
			(end 0.12065 -0.2794)
			(stroke
				(width 0.1)
				(type default)
			)
			(layer "B.Fab")
		)
		(fp_line
			(start -0.120396 0.3048)
			(end -0.120396 0.2794)
			(stroke
				(width 0.1)
				(type default)
			)
			(layer "B.Fab")
		)
		(fp_line
			(start -0.120396 0.2794)
			(end 0.12065 0.2794)
			(stroke
				(width 0.1)
				(type default)
			)
			(layer "B.Fab")
		)
		(fp_line
			(start -0.12065 -0.2794)
			(end -0.12065 -0.3048)
			(stroke
				(width 0.1)
				(type default)
			)
			(layer "B.Fab")
		)
		(fp_line
			(start -0.12065 -0.3048)
			(end -0.67945 -0.3048)
			(stroke
				(width 0.1)
				(type default)
			)
			(layer "B.Fab")
		)
		(fp_line
			(start -0.67945 0.3048)
			(end -0.120396 0.3048)
			(stroke
				(width 0.1)
				(type default)
			)
			(layer "B.Fab")
		)
		(fp_line
			(start -0.67945 -0.3048)
			(end -0.67945 0.3048)
			(stroke
				(width 0.1)
				(type default)
			)
			(layer "B.Fab")
		)
		(pad "1" smd circle
			(at 0.40005 0)
			(size 0 0)
			(layers "B.Cu" "B.Mask" "B.Paste")
			(net "PVDDCR_CPU0_P0")
		)
		(pad "2" smd circle
			(at -0.40005 0)
			(size 0 0)
			(layers "B.Cu" "B.Mask" "B.Paste")
			(net "GND")
		)
	)
)
